(kicad_pcb
	(version 20260206)
	(generator "pcbnew")
	(generator_version "10.0")
	(general
		(thickness 1.6)
		(legacy_teardrops no)
	)
	(paper "A4")
	(title_block
		(title "04192023_DAF0TMB3IC0_F0TG_MB_C_brd_V02_OCP.brd")
		(comment 1 "Grand Teton / footprints 5428-5436 of 8354")
	)
	(layers
		(0 "F.Cu" signal "TOP")
		(4 "In1.Cu" signal "GND")
		(6 "In2.Cu" signal "IN1")
		(8 "In3.Cu" signal "GND1")
		(10 "In4.Cu" signal "IN2")
		(12 "In5.Cu" signal "GND2")
		(14 "In6.Cu" signal "IN3")
		(16 "In7.Cu" signal "GND3")
		(18 "In8.Cu" signal "VCC")
		(20 "In9.Cu" signal "VCC1")
		(22 "In10.Cu" signal "GND4")
		(24 "In11.Cu" signal "IN4")
		(26 "In12.Cu" signal "GND5")
		(28 "In13.Cu" signal "IN5")
		(30 "In14.Cu" signal "GND6")
		(32 "In15.Cu" signal "IN6")
		(34 "In16.Cu" signal "GND7")
		(2 "B.Cu" signal "BOTTOM")
		(9 "F.Adhes" user "F.Adhesive")
		(11 "B.Adhes" user "B.Adhesive")
		(13 "F.Paste" user "Package Geometry/Pastemask Top")
		(15 "B.Paste" user "Package Geometry/Pastemask Bottom")
		(5 "F.SilkS" user "Ref Des/Silkscreen Top")
		(7 "B.SilkS" user "Ref Des/Silkscreen Bottom")
		(1 "F.Mask" user "Board Geometry/Soldermask Top")
		(3 "B.Mask" user "Board Geometry/Soldermask Bottom")
		(17 "Dwgs.User" user "User.Drawings")
		(19 "Cmts.User" user "User.Comments")
		(21 "Eco1.User" user "User.Eco1")
		(23 "Eco2.User" user "User.Eco2")
		(25 "Edge.Cuts" user "Board Geometry/Outline")
		(27 "Margin" user)
		(31 "F.CrtYd" user "Package Geometry/Place Bound Top")
		(29 "B.CrtYd" user "Package Geometry/Place Bound Bottom")
		(35 "F.Fab" user "Ref Des/Assembly Top")
		(33 "B.Fab" user "Ref Des/Assembly Bottom")
	)
	(footprint ""
		(layer "B.Cu")
		(at 244.348 -329.057 -90)
		(property "Reference" "C1077"
			(at 0 0 90)
			(layer "B.SilkS")
			(hide yes)
			(effects
				(font
					(size 1.27 1.27)
				)
				(justify mirror)
			)
		)
		(property "Value" ""
			(at 0 0 90)
			(layer "B.Fab")
			(effects
				(font
					(size 1.27 1.27)
				)
				(justify mirror)
			)
		)
		(duplicate_pad_numbers_are_jumpers no)
		(fp_line
			(start -1.524 0.762)
			(end 1.524 0.762)
			(stroke
				(width 0.1524)
				(type default)
			)
			(layer "B.SilkS")
		)
		(fp_line
			(start 1.524 0.762)
			(end 1.524 -0.762)
			(stroke
				(width 0.1524)
				(type default)
			)
			(layer "B.SilkS")
		)
		(fp_line
			(start -1.524 -0.762)
			(end -1.524 0.762)
			(stroke
				(width 0.1524)
				(type default)
			)
			(layer "B.SilkS")
		)
		(fp_line
			(start 1.524 -0.762)
			(end -1.524 -0.762)
			(stroke
				(width 0.1524)
				(type default)
			)
			(layer "B.SilkS")
		)
		(fp_line
			(start -1.1049 0.724916)
			(end -1.1049 -0.724916)
			(stroke
				(width 0.1)
				(type default)
			)
			(layer "B.Fab")
		)
		(fp_line
			(start 1.1049 0.724916)
			(end -1.1049 0.724916)
			(stroke
				(width 0.1)
				(type default)
			)
			(layer "B.Fab")
		)
		(fp_line
			(start -1.1049 -0.724916)
			(end 1.1049 -0.724916)
			(stroke
				(width 0.1)
				(type default)
			)
			(layer "B.Fab")
		)
		(fp_line
			(start 1.1049 -0.724916)
			(end 1.1049 0.724916)
			(stroke
				(width 0.1)
				(type default)
			)
			(layer "B.Fab")
		)
		(pad "1" smd rect
			(at 0.889 0 270)
			(size 1.016 1.27)
			(layers "B.Cu" "B.Mask" "B.Paste")
			(net "P3V3_MAX11617_2_VDD")
		)
		(pad "2" smd rect
			(at -0.889 0 270)
			(size 1.016 1.27)
			(layers "B.Cu" "B.Mask" "B.Paste")
			(net "GND")
		)
	)
	(footprint ""
		(layer "B.Cu")
		(at 148.206206 -386.766562 90)
		(property "Reference" "C425"
			(at 0 0 90)
			(layer "B.SilkS")
			(hide yes)
			(effects
				(font
					(size 1.27 1.27)
				)
				(justify mirror)
			)
		)
		(property "Value" ""
			(at 0 0 90)
			(layer "B.Fab")
			(effects
				(font
					(size 1.27 1.27)
				)
				(justify mirror)
			)
		)
		(duplicate_pad_numbers_are_jumpers no)
		(fp_line
			(start 0.299974 -0.150114)
			(end -0.299974 -0.150114)
			(stroke
				(width 0.1)
				(type default)
			)
			(layer "B.Fab")
		)
		(fp_line
			(start -0.299974 -0.150114)
			(end -0.299974 0.150114)
			(stroke
				(width 0.1)
				(type default)
			)
			(layer "B.Fab")
		)
		(fp_line
			(start 0.299974 0.150114)
			(end 0.299974 -0.150114)
			(stroke
				(width 0.1)
				(type default)
			)
			(layer "B.Fab")
		)
		(fp_line
			(start -0.299974 0.150114)
			(end 0.299974 0.150114)
			(stroke
				(width 0.1)
				(type default)
			)
			(layer "B.Fab")
		)
		(pad "1" smd rect
			(at 0.2667 0 270)
			(size 0.3048 0.381)
			(layers "B.Cu" "B.Mask" "B.Paste")
			(net "P0V9_CPU1_RT2_2A")
		)
		(pad "2" smd rect
			(at -0.2667 0 270)
			(size 0.3048 0.381)
			(layers "B.Cu" "B.Mask" "B.Paste")
			(net "GND")
		)
	)
	(footprint ""
		(layer "B.Cu")
		(at 395.516354 -401.624546 180)
		(property "Reference" "R1051"
			(at 0 0 0)
			(layer "B.SilkS")
			(hide yes)
			(effects
				(font
					(size 1.27 1.27)
				)
				(justify mirror)
			)
		)
		(property "Value" ""
			(at 0 0 0)
			(layer "B.Fab")
			(effects
				(font
					(size 1.27 1.27)
				)
				(justify mirror)
			)
		)
		(duplicate_pad_numbers_are_jumpers no)
		(fp_line
			(start 1.2954 0.5842)
			(end 1.2954 -0.5842)
			(stroke
				(width 0.1524)
				(type default)
			)
			(layer "B.SilkS")
		)
		(fp_line
			(start 1.2954 -0.5842)
			(end -1.2954 -0.5842)
			(stroke
				(width 0.1524)
				(type default)
			)
			(layer "B.SilkS")
		)
		(fp_line
			(start -1.2954 0.5842)
			(end 1.2954 0.5842)
			(stroke
				(width 0.1524)
				(type default)
			)
			(layer "B.SilkS")
		)
		(fp_line
			(start -1.2954 -0.5842)
			(end -1.2954 0.5842)
			(stroke
				(width 0.1524)
				(type default)
			)
			(layer "B.SilkS")
		)
		(fp_line
			(start 1.1938 0.4064)
			(end 1.1938 -0.406654)
			(stroke
				(width 0.1)
				(type default)
			)
			(layer "B.Fab")
		)
		(fp_line
			(start 1.1938 -0.406654)
			(end 0.8636 -0.406654)
			(stroke
				(width 0.1)
				(type default)
			)
			(layer "B.Fab")
		)
		(fp_line
			(start 0.8636 0.4572)
			(end 0.8636 0.4318)
			(stroke
				(width 0.1)
				(type default)
			)
			(layer "B.Fab")
		)
		(fp_line
			(start 0.8636 0.4318)
			(end 0.8636 0.4064)
			(stroke
				(width 0.1)
				(type default)
			)
			(layer "B.Fab")
		)
		(fp_line
			(start 0.8636 0.4064)
			(end 1.1938 0.4064)
			(stroke
				(width 0.1)
				(type default)
			)
			(layer "B.Fab")
		)
		(fp_line
			(start 0.8636 -0.406654)
			(end 0.8636 -0.4572)
			(stroke
				(width 0.1)
				(type default)
			)
			(layer "B.Fab")
		)
		(fp_line
			(start 0.8636 -0.4572)
			(end -0.8636 -0.4572)
			(stroke
				(width 0.1)
				(type default)
			)
			(layer "B.Fab")
		)
		(fp_line
			(start -0.8636 0.4572)
			(end 0.8636 0.4572)
			(stroke
				(width 0.1)
				(type default)
			)
			(layer "B.Fab")
		)
		(fp_line
			(start -0.8636 0.4064)
			(end -0.8636 0.4572)
			(stroke
				(width 0.1)
				(type default)
			)
			(layer "B.Fab")
		)
		(fp_line
			(start -0.8636 -0.406654)
			(end -1.1938 -0.406654)
			(stroke
				(width 0.1)
				(type default)
			)
			(layer "B.Fab")
		)
		(fp_line
			(start -0.8636 -0.4572)
			(end -0.8636 -0.406654)
			(stroke
				(width 0.1)
				(type default)
			)
			(layer "B.Fab")
		)
		(fp_line
			(start -1.1938 0.4064)
			(end -0.8636 0.4064)
			(stroke
				(width 0.1)
				(type default)
			)
			(layer "B.Fab")
		)
		(fp_line
			(start -1.1938 -0.406654)
			(end -1.1938 0.4064)
			(stroke
				(width 0.1)
				(type default)
			)
			(layer "B.Fab")
		)
		(pad "1" smd rect
			(at 0.7366 0 90)
			(size 0.7112 0.8128)
			(layers "B.Cu" "B.Mask" "B.Paste")
			(net "P0V9_CPU0_RT_2D")
		)
		(pad "2" smd rect
			(at -0.7366 0 90)
			(size 0.7112 0.8128)
			(layers "B.Cu" "B.Mask" "B.Paste")
			(net "P0V9_CPU0_RT2_2A_2D")
		)
	)
	(footprint ""
		(layer "B.Cu")
		(at 383.076958 -205.902052 -90)
		(property "Reference" "R987"
			(at 0 0 90)
			(layer "B.SilkS")
			(hide yes)
			(effects
				(font
					(size 1.27 1.27)
				)
				(justify mirror)
			)
		)
		(property "Value" ""
			(at 0 0 90)
			(layer "B.Fab")
			(effects
				(font
					(size 1.27 1.27)
				)
				(justify mirror)
			)
		)
		(duplicate_pad_numbers_are_jumpers no)
		(fp_line
			(start -0.7874 0.4064)
			(end 0.7874 0.4064)
			(stroke
				(width 0.1524)
				(type default)
			)
			(layer "B.SilkS")
		)
		(fp_line
			(start 0.7874 0.4064)
			(end 0.7874 -0.4064)
			(stroke
				(width 0.1524)
				(type default)
			)
			(layer "B.SilkS")
		)
		(fp_line
			(start -0.7874 -0.4064)
			(end -0.7874 0.4064)
			(stroke
				(width 0.1524)
				(type default)
			)
			(layer "B.SilkS")
		)
		(fp_line
			(start 0.7874 -0.4064)
			(end -0.7874 -0.4064)
			(stroke
				(width 0.1524)
				(type default)
			)
			(layer "B.SilkS")
		)
		(fp_line
			(start -0.67945 0.3048)
			(end -0.120396 0.3048)
			(stroke
				(width 0.1)
				(type default)
			)
			(layer "B.Fab")
		)
		(fp_line
			(start -0.120396 0.3048)
			(end -0.120396 0.2794)
			(stroke
				(width 0.1)
				(type default)
			)
			(layer "B.Fab")
		)
		(fp_line
			(start 0.12065 0.3048)
			(end 0.67945 0.3048)
			(stroke
				(width 0.1)
				(type default)
			)
			(layer "B.Fab")
		)
		(fp_line
			(start 0.67945 0.3048)
			(end 0.67945 -0.305054)
			(stroke
				(width 0.1)
				(type default)
			)
			(layer "B.Fab")
		)
		(fp_line
			(start -0.120396 0.2794)
			(end 0.12065 0.2794)
			(stroke
				(width 0.1)
				(type default)
			)
			(layer "B.Fab")
		)
		(fp_line
			(start 0.12065 0.2794)
			(end 0.12065 0.3048)
			(stroke
				(width 0.1)
				(type default)
			)
			(layer "B.Fab")
		)
		(fp_line
			(start -0.12065 -0.2794)
			(end -0.12065 -0.3048)
			(stroke
				(width 0.1)
				(type default)
			)
			(layer "B.Fab")
		)
		(fp_line
			(start 0.12065 -0.2794)
			(end -0.12065 -0.2794)
			(stroke
				(width 0.1)
				(type default)
			)
			(layer "B.Fab")
		)
		(fp_line
			(start -0.67945 -0.3048)
			(end -0.67945 0.3048)
			(stroke
				(width 0.1)
				(type default)
			)
			(layer "B.Fab")
		)
		(fp_line
			(start -0.12065 -0.3048)
			(end -0.67945 -0.3048)
			(stroke
				(width 0.1)
				(type default)
			)
			(layer "B.Fab")
		)
		(fp_line
			(start 0.12065 -0.305054)
			(end 0.12065 -0.2794)
			(stroke
				(width 0.1)
				(type default)
			)
			(layer "B.Fab")
		)
		(fp_line
			(start 0.67945 -0.305054)
			(end 0.12065 -0.305054)
			(stroke
				(width 0.1)
				(type default)
			)
			(layer "B.Fab")
		)
		(pad "1" smd rect
			(at 0.40005 0 270)
			(size 0.4572 0.508)
			(layers "B.Cu" "B.Mask" "B.Paste")
			(net "I3C_1_SPD_DDRGL_CPU0_R_SDA")
		)
		(pad "2" smd rect
			(at -0.40005 0 270)
			(size 0.4572 0.508)
			(layers "B.Cu" "B.Mask" "B.Paste")
			(net "I3C_SPD_DDRGL_CPU0_BYPASS_SDA")
		)
	)
	(footprint ""
		(layer "B.Cu")
		(at 307.0352 -428.0916 180)
		(property "Reference" "R1365"
			(at 0 0 0)
			(layer "B.SilkS")
			(hide yes)
			(effects
				(font
					(size 1.27 1.27)
				)
				(justify mirror)
			)
		)
		(property "Value" ""
			(at 0 0 0)
			(layer "B.Fab")
			(effects
				(font
					(size 1.27 1.27)
				)
				(justify mirror)
			)
		)
		(duplicate_pad_numbers_are_jumpers no)
		(fp_line
			(start 0.32512 0.175006)
			(end 0.32512 -0.175006)
			(stroke
				(width 0.1)
				(type default)
			)
			(layer "B.Fab")
		)
		(fp_line
			(start 0.32512 -0.175006)
			(end -0.32512 -0.175006)
			(stroke
				(width 0.1)
				(type default)
			)
			(layer "B.Fab")
		)
		(fp_line
			(start -0.32512 0.175006)
			(end 0.32512 0.175006)
			(stroke
				(width 0.1)
				(type default)
			)
			(layer "B.Fab")
		)
		(fp_line
			(start -0.32512 -0.175006)
			(end -0.32512 0.175006)
			(stroke
				(width 0.1)
				(type default)
			)
			(layer "B.Fab")
		)
		(pad "1" smd rect
			(at 0.2667 0)
			(size 0.3048 0.381)
			(layers "B.Cu" "B.Mask" "B.Paste")
			(net "JTAG_TCK_RT_CPU0_P0")
		)
		(pad "2" smd rect
			(at -0.2667 0 180)
			(size 0.3048 0.381)
			(layers "B.Cu" "B.Mask" "B.Paste")
			(net "GND")
		)
	)
	(footprint ""
		(layer "B.Cu")
		(at 439.42 -356.235 180)
		(property "Reference" "PC8004"
			(at 0 0 0)
			(layer "B.SilkS")
			(hide yes)
			(effects
				(font
					(size 1.27 1.27)
				)
				(justify mirror)
			)
		)
		(property "Value" ""
			(at 0 0 0)
			(layer "B.Fab")
			(effects
				(font
					(size 1.27 1.27)
				)
				(justify mirror)
			)
		)
		(duplicate_pad_numbers_are_jumpers no)
		(fp_line
			(start 1.524 0.762)
			(end 1.524 -0.762)
			(stroke
				(width 0.1524)
				(type default)
			)
			(layer "B.SilkS")
		)
		(fp_line
			(start 1.524 -0.762)
			(end -1.524 -0.762)
			(stroke
				(width 0.1524)
				(type default)
			)
			(layer "B.SilkS")
		)
		(fp_line
			(start -1.524 0.762)
			(end 1.524 0.762)
			(stroke
				(width 0.1524)
				(type default)
			)
			(layer "B.SilkS")
		)
		(fp_line
			(start -1.524 -0.762)
			(end -1.524 0.762)
			(stroke
				(width 0.1524)
				(type default)
			)
			(layer "B.SilkS")
		)
		(fp_line
			(start 1.1049 0.724916)
			(end -1.1049 0.724916)
			(stroke
				(width 0.1)
				(type default)
			)
			(layer "B.Fab")
		)
		(fp_line
			(start 1.1049 -0.724916)
			(end 1.1049 0.724916)
			(stroke
				(width 0.1)
				(type default)
			)
			(layer "B.Fab")
		)
		(fp_line
			(start -1.1049 0.724916)
			(end -1.1049 -0.724916)
			(stroke
				(width 0.1)
				(type default)
			)
			(layer "B.Fab")
		)
		(fp_line
			(start -1.1049 -0.724916)
			(end 1.1049 -0.724916)
			(stroke
				(width 0.1)
				(type default)
			)
			(layer "B.Fab")
		)
		(pad "1" smd rect
			(at 0.889 0 180)
			(size 1.016 1.27)
			(layers "B.Cu" "B.Mask" "B.Paste")
			(net "SW_P12V_AUX_PVDD11_S3_P0_FLT")
		)
		(pad "2" smd rect
			(at -0.889 0 180)
			(size 1.016 1.27)
			(layers "B.Cu" "B.Mask" "B.Paste")
			(net "GND")
		)
	)
	(footprint ""
		(layer "B.Cu")
		(at 397.623538 -393.96416 180)
		(property "Reference" "R1073"
			(at 0 0 0)
			(layer "B.SilkS")
			(hide yes)
			(effects
				(font
					(size 1.27 1.27)
				)
				(justify mirror)
			)
		)
		(property "Value" ""
			(at 0 0 0)
			(layer "B.Fab")
			(effects
				(font
					(size 1.27 1.27)
				)
				(justify mirror)
			)
		)
		(duplicate_pad_numbers_are_jumpers no)
		(fp_line
			(start 0.32512 0.175006)
			(end 0.32512 -0.175006)
			(stroke
				(width 0.1)
				(type default)
			)
			(layer "B.Fab")
		)
		(fp_line
			(start 0.32512 -0.175006)
			(end -0.32512 -0.175006)
			(stroke
				(width 0.1)
				(type default)
			)
			(layer "B.Fab")
		)
		(fp_line
			(start -0.32512 0.175006)
			(end 0.32512 0.175006)
			(stroke
				(width 0.1)
				(type default)
			)
			(layer "B.Fab")
		)
		(fp_line
			(start -0.32512 -0.175006)
			(end -0.32512 0.175006)
			(stroke
				(width 0.1)
				(type default)
			)
			(layer "B.Fab")
		)
		(pad "1" smd rect
			(at 0.2667 0)
			(size 0.3048 0.381)
			(layers "B.Cu" "B.Mask" "B.Paste")
			(net "P1V8_CPU0_RT_1D")
		)
		(pad "2" smd rect
			(at -0.2667 0 180)
			(size 0.3048 0.381)
			(layers "B.Cu" "B.Mask" "B.Paste")
			(net "TEST0_RT_CPU0_P2")
		)
	)
	(footprint ""
		(layer "B.Cu")
		(at 240.792 -217.678 -90)
		(property "Reference" "R78"
			(at 0 0 90)
			(layer "B.SilkS")
			(hide yes)
			(effects
				(font
					(size 1.27 1.27)
				)
				(justify mirror)
			)
		)
		(property "Value" ""
			(at 0 0 90)
			(layer "B.Fab")
			(effects
				(font
					(size 1.27 1.27)
				)
				(justify mirror)
			)
		)
		(duplicate_pad_numbers_are_jumpers no)
		(fp_line
			(start -0.7874 0.4064)
			(end 0.7874 0.4064)
			(stroke
				(width 0.1524)
				(type default)
			)
			(layer "B.SilkS")
		)
		(fp_line
			(start 0.7874 0.4064)
			(end 0.7874 -0.4064)
			(stroke
				(width 0.1524)
				(type default)
			)
			(layer "B.SilkS")
		)
		(fp_line
			(start -0.7874 -0.4064)
			(end -0.7874 0.4064)
			(stroke
				(width 0.1524)
				(type default)
			)
			(layer "B.SilkS")
		)
		(fp_line
			(start 0.7874 -0.4064)
			(end -0.7874 -0.4064)
			(stroke
				(width 0.1524)
				(type default)
			)
			(layer "B.SilkS")
		)
		(fp_line
			(start -0.67945 0.3048)
			(end -0.120396 0.3048)
			(stroke
				(width 0.1)
				(type default)
			)
			(layer "B.Fab")
		)
		(fp_line
			(start -0.120396 0.3048)
			(end -0.120396 0.2794)
			(stroke
				(width 0.1)
				(type default)
			)
			(layer "B.Fab")
		)
		(fp_line
			(start 0.12065 0.3048)
			(end 0.67945 0.3048)
			(stroke
				(width 0.1)
				(type default)
			)
			(layer "B.Fab")
		)
		(fp_line
			(start 0.67945 0.3048)
			(end 0.67945 -0.305054)
			(stroke
				(width 0.1)
				(type default)
			)
			(layer "B.Fab")
		)
		(fp_line
			(start -0.120396 0.2794)
			(end 0.12065 0.2794)
			(stroke
				(width 0.1)
				(type default)
			)
			(layer "B.Fab")
		)
		(fp_line
			(start 0.12065 0.2794)
			(end 0.12065 0.3048)
			(stroke
				(width 0.1)
				(type default)
			)
			(layer "B.Fab")
		)
		(fp_line
			(start -0.12065 -0.2794)
			(end -0.12065 -0.3048)
			(stroke
				(width 0.1)
				(type default)
			)
			(layer "B.Fab")
		)
		(fp_line
			(start 0.12065 -0.2794)
			(end -0.12065 -0.2794)
			(stroke
				(width 0.1)
				(type default)
			)
			(layer "B.Fab")
		)
		(fp_line
			(start -0.67945 -0.3048)
			(end -0.67945 0.3048)
			(stroke
				(width 0.1)
				(type default)
			)
			(layer "B.Fab")
		)
		(fp_line
			(start -0.12065 -0.3048)
			(end -0.67945 -0.3048)
			(stroke
				(width 0.1)
				(type default)
			)
			(layer "B.Fab")
		)
		(fp_line
			(start 0.12065 -0.305054)
			(end 0.12065 -0.2794)
			(stroke
				(width 0.1)
				(type default)
			)
			(layer "B.Fab")
		)
		(fp_line
			(start 0.67945 -0.305054)
			(end 0.12065 -0.305054)
			(stroke
				(width 0.1)
				(type default)
			)
			(layer "B.Fab")
		)
		(pad "1" smd circle
			(at 0.40005 0 90)
			(size 0 0)
			(layers "B.Cu" "B.Mask" "B.Paste")
			(net "P3V3")
		)
		(pad "2" smd circle
			(at -0.40005 0 90)
			(size 0 0)
			(layers "B.Cu" "B.Mask" "B.Paste")
			(net "PU_U5_EN")
		)
	)
	(footprint ""
		(layer "B.Cu")
		(at 331.20584 -326.311006 -90)
		(property "Reference" "PC105_1"
			(at 0 0 90)
			(layer "B.SilkS")
			(hide yes)
			(effects
				(font
					(size 1.27 1.27)
				)
				(justify mirror)
			)
		)
		(property "Value" ""
			(at 0 0 90)
			(layer "B.Fab")
			(effects
				(font
					(size 1.27 1.27)
				)
				(justify mirror)
			)
		)
		(duplicate_pad_numbers_are_jumpers no)
		(fp_line
			(start -1.524 0.762)
			(end 1.524 0.762)
			(stroke
				(width 0.1524)
				(type default)
			)
			(layer "B.SilkS")
		)
		(fp_line
			(start 1.524 0.762)
			(end 1.524 -0.762)
			(stroke
				(width 0.1524)
				(type default)
			)
			(layer "B.SilkS")
		)
		(fp_line
			(start -1.524 -0.762)
			(end -1.524 0.762)
			(stroke
				(width 0.1524)
				(type default)
			)
			(layer "B.SilkS")
		)
		(fp_line
			(start 1.524 -0.762)
			(end -1.524 -0.762)
			(stroke
				(width 0.1524)
				(type default)
			)
			(layer "B.SilkS")
		)
		(fp_line
			(start -1.1049 0.724916)
			(end -1.1049 -0.724916)
			(stroke
				(width 0.1)
				(type default)
			)
			(layer "B.Fab")
		)
		(fp_line
			(start 1.1049 0.724916)
			(end -1.1049 0.724916)
			(stroke
				(width 0.1)
				(type default)
			)
			(layer "B.Fab")
		)
		(fp_line
			(start -1.1049 -0.724916)
			(end 1.1049 -0.724916)
			(stroke
				(width 0.1)
				(type default)
			)
			(layer "B.Fab")
		)
		(fp_line
			(start 1.1049 -0.724916)
			(end 1.1049 0.724916)
			(stroke
				(width 0.1)
				(type default)
			)
			(layer "B.Fab")
		)
		(pad "1" smd rect
			(at 0.889 0 270)
			(size 1.016 1.27)
			(layers "B.Cu" "B.Mask" "B.Paste")
			(net "PVDDCR_CPU1_P0")
		)
		(pad "2" smd rect
			(at -0.889 0 270)
			(size 1.016 1.27)
			(layers "B.Cu" "B.Mask" "B.Paste")
			(net "GND")
		)
	)
)
